# BASEBOARD_FAB2 (Tioga Pass) — schematic netlist excerpt (pin names and nets, part order shuffled) for the footprints in the layout excerpt that follows; sources: Cadence DE-HDL packaged netlist, KiCad conversion of Wiwynn_Tioga_Pass_MB.brd

C1D13  CAP_A  0.1UF 16V 10% X7R  pkg 0402V  page 208 : A = VR_FET_SW_P12V_STBY_PVCCIN_CPU1 ; B = GND
R1C21  RES  10.0 1% CHIP  pkg 0402  page 206 : A = VSENSE_PVSA_CPU1_P ; B = VSENSE_PVSA_CPU1_BVSP
C1C24  CAP  0.220UF 16V 10% X7R  pkg 0402  page 209 : A = VR_PVCCIN_CPU1_PH5_BOOT ; B = VR_PVCCIN_CPU1_PH5_PHASE

(kicad_pcb
	(version 20260206)
	(generator "pcbnew")
	(generator_version "10.0")
	(general
		(thickness 1.6)
		(legacy_teardrops no)
	)
	(paper "A4")
	(title_block
		(title "Wiwynn_Tioga_Pass_MB.brd")
		(comment 1 "Tioga Pass / footprints 1226-1228 of 4770")
	)
	(layers
		(0 "F.Cu" signal "TOP")
		(4 "In1.Cu" signal "L2GND")
		(6 "In2.Cu" signal "L3")
		(8 "In3.Cu" signal "L4GND")
		(10 "In4.Cu" signal "L5")
		(12 "In5.Cu" signal "L6GND")
		(14 "In6.Cu" signal "L7VCC")
		(16 "In7.Cu" signal "L8VCC")
		(18 "In8.Cu" signal "L9GND")
		(20 "In9.Cu" signal "L10")
		(22 "In10.Cu" signal "L11GND")
		(24 "In11.Cu" signal "L12")
		(26 "In12.Cu" signal "L13GND")
		(2 "B.Cu" signal "BOTTOM")
		(9 "F.Adhes" user "F.Adhesive")
		(11 "B.Adhes" user "B.Adhesive")
		(13 "F.Paste" user "Package Geometry/Pastemask Top")
		(15 "B.Paste" user "Package Geometry/Pastemask Bottom")
		(5 "F.SilkS" user "Ref Des/Silkscreen Top")
		(7 "B.SilkS" user "Ref Des/Silkscreen Bottom")
		(1 "F.Mask" user "Board Geometry/Soldermask Top")
		(3 "B.Mask" user "Board Geometry/Soldermask Bottom")
		(17 "Dwgs.User" user "User.Drawings")
		(19 "Cmts.User" user "User.Comments")
		(21 "Eco1.User" user "User.Eco1")
		(23 "Eco2.User" user "User.Eco2")
		(25 "Edge.Cuts" user "Board Geometry/Outline")
		(27 "Margin" user)
		(31 "F.CrtYd" user "Package Geometry/Place Bound Top")
		(29 "B.CrtYd" user "Package Geometry/Place Bound Bottom")
		(35 "F.Fab" user "Ref Des/Assembly Top")
		(33 "B.Fab" user "Ref Des/Assembly Bottom")
	)
	(footprint ""
		(layer "F.Cu")
		(at 24.230584 -95.827596)
		(property "Reference" "R1C21"
			(at 0 0 0)
			(layer "F.SilkS")
			(hide yes)
			(effects
				(font
					(size 1.27 1.27)
				)
			)
		)
		(property "Value" ""
			(at 0 0 0)
			(layer "F.Fab")
			(effects
				(font
					(size 1.27 1.27)
				)
			)
		)
		(duplicate_pad_numbers_are_jumpers no)
		(fp_rect
			(start -0.2794 0.9906)
			(end 0.2794 -0.1016)
			(stroke
				(width 0)
				(type default)
			)
			(fill no)
			(layer "F.CrtYd")
		)
		(fp_line
			(start -0.2794 -0.1016)
			(end -0.2794 0.9906)
			(stroke
				(width 0.1)
				(type default)
			)
			(layer "F.Fab")
		)
		(fp_line
			(start -0.2794 0.9906)
			(end 0.2794 0.9906)
			(stroke
				(width 0.1)
				(type default)
			)
			(layer "F.Fab")
		)
		(fp_line
			(start 0.2794 -0.1016)
			(end -0.2794 -0.1016)
			(stroke
				(width 0.1)
				(type default)
			)
			(layer "F.Fab")
		)
		(fp_line
			(start 0.2794 0.9906)
			(end 0.2794 -0.1016)
			(stroke
				(width 0.1)
				(type default)
			)
			(layer "F.Fab")
		)
		(pad "1" smd rect
			(at 0 0)
			(size 0.508 0.508)
			(layers "F.Cu" "F.Mask" "F.Paste")
			(net "VSENSE_PVSA_CPU1_P")
		)
		(pad "2" smd rect
			(at 0 0.889)
			(size 0.508 0.508)
			(layers "F.Cu" "F.Mask" "F.Paste")
			(net "VSENSE_PVSA_CPU1_BVSP")
		)
		(zone
			(layer "F.Cu")
			(hatch none 0.5)
			(connect_pads
				(clearance 0)
			)
			(min_thickness 0.25)
			(keepout
				(tracks allowed)
				(vias not_allowed)
				(pads allowed)
				(copperpour not_allowed)
				(footprints allowed)
			)
			(placement
				(enabled no)
				(sheetname "")
			)
			(fill
				(thermal_gap 0.5)
				(thermal_bridge_width 0.5)
				(island_removal_mode 0)
			)
			(polygon
				(pts
					(xy 23.976584 -95.192596) (xy 24.484584 -95.192596) (xy 24.484584 -95.573596) (xy 23.976584 -95.573596)
				)
			)
		)
		(zone
			(layer "F.Cu")
			(hatch none 0.5)
			(connect_pads
				(clearance 0)
			)
			(min_thickness 0.25)
			(keepout
				(tracks not_allowed)
				(vias allowed)
				(pads allowed)
				(copperpour not_allowed)
				(footprints allowed)
			)
			(placement
				(enabled no)
				(sheetname "")
			)
			(fill
				(thermal_gap 0.5)
				(thermal_bridge_width 0.5)
				(island_removal_mode 0)
			)
			(polygon
				(pts
					(xy 23.976584 -95.192596) (xy 24.484584 -95.192596) (xy 24.484584 -95.573596) (xy 23.976584 -95.573596)
				)
			)
		)
	)
	(footprint ""
		(layer "F.Cu")
		(at 28.194 -91.567 90)
		(property "Reference" "C1C24"
			(at 0 0 90)
			(layer "F.SilkS")
			(hide yes)
			(effects
				(font
					(size 1.27 1.27)
				)
			)
		)
		(property "Value" ""
			(at 0 0 90)
			(layer "F.Fab")
			(effects
				(font
					(size 1.27 1.27)
				)
			)
		)
		(duplicate_pad_numbers_are_jumpers no)
		(fp_rect
			(start -0.3048 0.9906)
			(end 0.3048 -0.1016)
			(stroke
				(width 0)
				(type default)
			)
			(fill no)
			(layer "F.CrtYd")
		)
		(fp_line
			(start 0.3048 -0.1016)
			(end -0.3048 -0.1016)
			(stroke
				(width 0.1)
				(type default)
			)
			(layer "F.Fab")
		)
		(fp_line
			(start -0.3048 -0.1016)
			(end -0.3048 0.9906)
			(stroke
				(width 0.1)
				(type default)
			)
			(layer "F.Fab")
		)
		(fp_line
			(start 0.3048 0.9906)
			(end 0.3048 -0.1016)
			(stroke
				(width 0.1)
				(type default)
			)
			(layer "F.Fab")
		)
		(fp_line
			(start -0.3048 0.9906)
			(end 0.3048 0.9906)
			(stroke
				(width 0.1)
				(type default)
			)
			(layer "F.Fab")
		)
		(pad "1" smd rect
			(at 0 0 90)
			(size 0.508 0.508)
			(layers "F.Cu" "F.Mask" "F.Paste")
			(net "VR_PVCCIN_CPU1_PH5_BOOT")
		)
		(pad "2" smd rect
			(at 0 0.889 90)
			(size 0.508 0.508)
			(layers "F.Cu" "F.Mask" "F.Paste")
			(net "VR_PVCCIN_CPU1_PH5_PHASE")
		)
		(zone
			(layer "F.Cu")
			(hatch none 0.5)
			(connect_pads
				(clearance 0)
			)
			(min_thickness 0.25)
			(keepout
				(tracks not_allowed)
				(vias allowed)
				(pads allowed)
				(copperpour not_allowed)
				(footprints allowed)
			)
			(placement
				(enabled no)
				(sheetname "")
			)
			(fill
				(thermal_gap 0.5)
				(thermal_bridge_width 0.5)
				(island_removal_mode 0)
			)
			(polygon
				(pts
					(xy 28.829 -91.313) (xy 28.829 -91.821) (xy 28.448 -91.821) (xy 28.448 -91.313)
				)
			)
		)
		(zone
			(layer "F.Cu")
			(hatch none 0.5)
			(connect_pads
				(clearance 0)
			)
			(min_thickness 0.25)
			(keepout
				(tracks allowed)
				(vias not_allowed)
				(pads allowed)
				(copperpour not_allowed)
				(footprints allowed)
			)
			(placement
				(enabled no)
				(sheetname "")
			)
			(fill
				(thermal_gap 0.5)
				(thermal_bridge_width 0.5)
				(island_removal_mode 0)
			)
			(polygon
				(pts
					(xy 28.829 -91.313) (xy 28.829 -91.821) (xy 28.448 -91.821) (xy 28.448 -91.313)
				)
			)
		)
	)
	(footprint ""
		(layer "F.Cu")
		(at 33.2105 -84.836 90)
		(property "Reference" "C1D13"
			(at 0 0 90)
			(layer "F.SilkS")
			(hide yes)
			(effects
				(font
					(size 1.27 1.27)
				)
			)
		)
		(property "Value" ""
			(at 0 0 90)
			(layer "F.Fab")
			(effects
				(font
					(size 1.27 1.27)
				)
			)
		)
		(duplicate_pad_numbers_are_jumpers no)
		(fp_rect
			(start 0.3048 0.9906)
			(end -0.3048 -0.1016)
			(stroke
				(width 0)
				(type default)
			)
			(fill no)
			(layer "F.CrtYd")
		)
		(fp_line
			(start 0.3048 -0.1016)
			(end -0.3048 -0.1016)
			(stroke
				(width 0.1)
				(type default)
			)
			(layer "F.Fab")
		)
		(fp_line
			(start -0.3048 -0.1016)
			(end -0.3048 0.9906)
			(stroke
				(width 0.1)
				(type default)
			)
			(layer "F.Fab")
		)
		(fp_line
			(start 0.3048 0.9906)
			(end 0.3048 -0.1016)
			(stroke
				(width 0.1)
				(type default)
			)
			(layer "F.Fab")
		)
		(fp_line
			(start -0.3048 0.9906)
			(end 0.3048 0.9906)
			(stroke
				(width 0.1)
				(type default)
			)
			(layer "F.Fab")
		)
		(pad "1" smd rect
			(at 0 0 90)
			(size 0.508 0.508)
			(layers "F.Cu" "F.Mask" "F.Paste")
			(net "VR_FET_SW_P12V_STBY_PVCCIN_CPU1")
		)
		(pad "2" smd rect
			(at 0 0.889 90)
			(size 0.508 0.508)
			(layers "F.Cu" "F.Mask" "F.Paste")
			(net "GND")
		)
		(zone
			(layer "F.Cu")
			(hatch none 0.5)
			(connect_pads
				(clearance 0)
			)
			(min_thickness 0.25)
			(keepout
				(tracks allowed)
				(vias not_allowed)
				(pads allowed)
				(copperpour not_allowed)
				(footprints allowed)
			)
			(placement
				(enabled no)
				(sheetname "")
			)
			(fill
				(thermal_gap 0.5)
				(thermal_bridge_width 0.5)
				(island_removal_mode 0)
			)
			(polygon
				(pts
					(xy 33.8455 -85.09) (xy 33.4645 -85.09) (xy 33.4645 -84.582) (xy 33.8455 -84.582)
				)
			)
		)
		(zone
			(layer "F.Cu")
			(hatch none 0.5)
			(connect_pads
				(clearance 0)
			)
			(min_thickness 0.25)
			(keepout
				(tracks not_allowed)
				(vias allowed)
				(pads allowed)
				(copperpour not_allowed)
				(footprints allowed)
			)
			(placement
				(enabled no)
				(sheetname "")
			)
			(fill
				(thermal_gap 0.5)
				(thermal_bridge_width 0.5)
				(island_removal_mode 0)
			)
			(polygon
				(pts
					(xy 33.8455 -85.09) (xy 33.4645 -85.09) (xy 33.4645 -84.582) (xy 33.8455 -84.582)
				)
			)
		)
	)
)
